(kicad_pcb
	(version 20260206)
	(generator "pcbnew")
	(generator_version "10.0")
	(general
		(thickness 1.6)
		(legacy_teardrops no)
	)
	(paper "A4")
	(title_block
		(title "04192023_DAF0TMB3IC0_F0TG_MB_C_brd_V02_OCP.brd")
		(comment 1 "Grand Teton / footprints 3067-3072 of 8354")
	)
	(layers
		(0 "F.Cu" signal "TOP")
		(4 "In1.Cu" signal "GND")
		(6 "In2.Cu" signal "IN1")
		(8 "In3.Cu" signal "GND1")
		(10 "In4.Cu" signal "IN2")
		(12 "In5.Cu" signal "GND2")
		(14 "In6.Cu" signal "IN3")
		(16 "In7.Cu" signal "GND3")
		(18 "In8.Cu" signal "VCC")
		(20 "In9.Cu" signal "VCC1")
		(22 "In10.Cu" signal "GND4")
		(24 "In11.Cu" signal "IN4")
		(26 "In12.Cu" signal "GND5")
		(28 "In13.Cu" signal "IN5")
		(30 "In14.Cu" signal "GND6")
		(32 "In15.Cu" signal "IN6")
		(34 "In16.Cu" signal "GND7")
		(2 "B.Cu" signal "BOTTOM")
		(9 "F.Adhes" user "F.Adhesive")
		(11 "B.Adhes" user "B.Adhesive")
		(13 "F.Paste" user "Package Geometry/Pastemask Top")
		(15 "B.Paste" user "Package Geometry/Pastemask Bottom")
		(5 "F.SilkS" user "Ref Des/Silkscreen Top")
		(7 "B.SilkS" user "Ref Des/Silkscreen Bottom")
		(1 "F.Mask" user "Board Geometry/Soldermask Top")
		(3 "B.Mask" user "Board Geometry/Soldermask Bottom")
		(17 "Dwgs.User" user "User.Drawings")
		(19 "Cmts.User" user "User.Comments")
		(21 "Eco1.User" user "User.Eco1")
		(23 "Eco2.User" user "User.Eco2")
		(25 "Edge.Cuts" user "Board Geometry/Outline")
		(27 "Margin" user)
		(31 "F.CrtYd" user "Package Geometry/Place Bound Top")
		(29 "B.CrtYd" user "Package Geometry/Place Bound Bottom")
		(35 "F.Fab" user "Ref Des/Assembly Top")
		(33 "B.Fab" user "Ref Des/Assembly Bottom")
	)
	(footprint ""
		(layer "F.Cu")
		(at 244.327426 -282.075636)
		(property "Reference" "PC6802"
			(at 0 0 0)
			(layer "F.SilkS")
			(hide yes)
			(effects
				(font
					(size 1.27 1.27)
				)
			)
		)
		(property "Value" ""
			(at 0 0 0)
			(layer "F.Fab")
			(effects
				(font
					(size 1.27 1.27)
				)
			)
		)
		(duplicate_pad_numbers_are_jumpers no)
		(fp_line
			(start -1.524 -0.762)
			(end 1.524 -0.762)
			(stroke
				(width 0.1524)
				(type default)
			)
			(layer "F.SilkS")
		)
		(fp_line
			(start -1.524 0.762)
			(end -1.524 -0.762)
			(stroke
				(width 0.1524)
				(type default)
			)
			(layer "F.SilkS")
		)
		(fp_line
			(start 1.524 -0.762)
			(end 1.524 0.762)
			(stroke
				(width 0.1524)
				(type default)
			)
			(layer "F.SilkS")
		)
		(fp_line
			(start 1.524 0.762)
			(end -1.524 0.762)
			(stroke
				(width 0.1524)
				(type default)
			)
			(layer "F.SilkS")
		)
		(fp_line
			(start -1.1049 -0.724916)
			(end -1.1049 0.724916)
			(stroke
				(width 0.1)
				(type default)
			)
			(layer "F.Fab")
		)
		(fp_line
			(start -1.1049 0.724916)
			(end 1.1049 0.724916)
			(stroke
				(width 0.1)
				(type default)
			)
			(layer "F.Fab")
		)
		(fp_line
			(start 1.1049 -0.724916)
			(end -1.1049 -0.724916)
			(stroke
				(width 0.1)
				(type default)
			)
			(layer "F.Fab")
		)
		(fp_line
			(start 1.1049 0.724916)
			(end 1.1049 -0.724916)
			(stroke
				(width 0.1)
				(type default)
			)
			(layer "F.Fab")
		)
		(pad "1" smd rect
			(at -0.889 0 180)
			(size 1.016 1.27)
			(layers "F.Cu" "F.Mask" "F.Paste")
			(net "SW_P12V_AUX_P1V8_RETIMER_CPU0_FLT")
		)
		(pad "2" smd rect
			(at 0.889 0 180)
			(size 1.016 1.27)
			(layers "F.Cu" "F.Mask" "F.Paste")
			(net "GND")
		)
	)
	(footprint ""
		(layer "F.Cu")
		(at 124.633228 -49.153064)
		(property "Reference" "R4452"
			(at 0 0 0)
			(layer "F.SilkS")
			(hide yes)
			(effects
				(font
					(size 1.27 1.27)
				)
			)
		)
		(property "Value" ""
			(at 0 0 0)
			(layer "F.Fab")
			(effects
				(font
					(size 1.27 1.27)
				)
			)
		)
		(duplicate_pad_numbers_are_jumpers no)
		(fp_line
			(start -0.7874 -0.4064)
			(end 0.7874 -0.4064)
			(stroke
				(width 0.1524)
				(type default)
			)
			(layer "F.SilkS")
		)
		(fp_line
			(start -0.7874 0.4064)
			(end -0.7874 -0.4064)
			(stroke
				(width 0.1524)
				(type default)
			)
			(layer "F.SilkS")
		)
		(fp_line
			(start 0.7874 -0.4064)
			(end 0.7874 0.4064)
			(stroke
				(width 0.1524)
				(type default)
			)
			(layer "F.SilkS")
		)
		(fp_line
			(start 0.7874 0.4064)
			(end -0.7874 0.4064)
			(stroke
				(width 0.1524)
				(type default)
			)
			(layer "F.SilkS")
		)
		(fp_line
			(start -0.67945 -0.305054)
			(end -0.12065 -0.305054)
			(stroke
				(width 0.1)
				(type default)
			)
			(layer "F.Fab")
		)
		(fp_line
			(start -0.67945 0.3048)
			(end -0.67945 -0.305054)
			(stroke
				(width 0.1)
				(type default)
			)
			(layer "F.Fab")
		)
		(fp_line
			(start -0.12065 -0.305054)
			(end -0.12065 -0.2794)
			(stroke
				(width 0.1)
				(type default)
			)
			(layer "F.Fab")
		)
		(fp_line
			(start -0.12065 -0.2794)
			(end 0.12065 -0.2794)
			(stroke
				(width 0.1)
				(type default)
			)
			(layer "F.Fab")
		)
		(fp_line
			(start -0.12065 0.2794)
			(end -0.12065 0.3048)
			(stroke
				(width 0.1)
				(type default)
			)
			(layer "F.Fab")
		)
		(fp_line
			(start -0.12065 0.3048)
			(end -0.67945 0.3048)
			(stroke
				(width 0.1)
				(type default)
			)
			(layer "F.Fab")
		)
		(fp_line
			(start 0.120396 0.2794)
			(end -0.12065 0.2794)
			(stroke
				(width 0.1)
				(type default)
			)
			(layer "F.Fab")
		)
		(fp_line
			(start 0.120396 0.3048)
			(end 0.120396 0.2794)
			(stroke
				(width 0.1)
				(type default)
			)
			(layer "F.Fab")
		)
		(fp_line
			(start 0.12065 -0.3048)
			(end 0.67945 -0.3048)
			(stroke
				(width 0.1)
				(type default)
			)
			(layer "F.Fab")
		)
		(fp_line
			(start 0.12065 -0.2794)
			(end 0.12065 -0.3048)
			(stroke
				(width 0.1)
				(type default)
			)
			(layer "F.Fab")
		)
		(fp_line
			(start 0.67945 -0.3048)
			(end 0.67945 0.3048)
			(stroke
				(width 0.1)
				(type default)
			)
			(layer "F.Fab")
		)
		(fp_line
			(start 0.67945 0.3048)
			(end 0.120396 0.3048)
			(stroke
				(width 0.1)
				(type default)
			)
			(layer "F.Fab")
		)
		(pad "1" smd circle
			(at -0.40005 0)
			(size 0 0)
			(layers "F.Cu" "F.Mask" "F.Paste")
			(net "P3V3_AUX")
		)
		(pad "2" smd circle
			(at 0.40005 0)
			(size 0 0)
			(layers "F.Cu" "F.Mask" "F.Paste")
			(net "RST_USB_CPU0_HUB1_R_N")
		)
	)
	(footprint ""
		(layer "F.Cu")
		(at 111.86541 -58.827162)
		(property "Reference" "U160"
			(at -2.482088 -3.213862 0)
			(unlocked yes)
			(layer "F.SilkS")
			(effects
				(font
					(size 0.7874 0.5842)
					(thickness 0.1524)
				)
				(justify left)
			)
		)
		(property "Value" ""
			(at 0 0 0)
			(layer "F.Fab")
			(effects
				(font
					(size 1.27 1.27)
				)
			)
		)
		(duplicate_pad_numbers_are_jumpers no)
		(fp_line
			(start -2.112264 -2.549906)
			(end -0.704088 -2.549906)
			(stroke
				(width 0.1524)
				(type default)
			)
			(layer "F.SilkS")
		)
		(fp_line
			(start -2.112264 2.549906)
			(end -2.112264 -2.549906)
			(stroke
				(width 0.1524)
				(type default)
			)
			(layer "F.SilkS")
		)
		(fp_line
			(start -0.704088 -2.549906)
			(end 0 -1.845818)
			(stroke
				(width 0.1524)
				(type default)
			)
			(layer "F.SilkS")
		)
		(fp_line
			(start 0 -1.845818)
			(end 0.704088 -2.549906)
			(stroke
				(width 0.1524)
				(type default)
			)
			(layer "F.SilkS")
		)
		(fp_line
			(start 0.704088 -2.549906)
			(end 2.112264 -2.549906)
			(stroke
				(width 0.1524)
				(type default)
			)
			(layer "F.SilkS")
		)
		(fp_line
			(start 2.112264 -2.549906)
			(end 2.112264 2.549906)
			(stroke
				(width 0.1524)
				(type default)
			)
			(layer "F.SilkS")
		)
		(fp_line
			(start 2.112264 2.549906)
			(end -2.112264 2.549906)
			(stroke
				(width 0.1524)
				(type default)
			)
			(layer "F.SilkS")
		)
		(fp_poly
			(pts
				(xy -4.917186 -2.8829) (xy -4.917186 -1.8669) (xy -3.901186 -2.3749)
			)
			(stroke
				(width 0)
				(type default)
			)
			(fill yes)
			(layer "F.SilkS")
		)
		(fp_line
			(start -2.249932 -2.549906)
			(end 2.249932 -2.549906)
			(stroke
				(width 0.1)
				(type default)
			)
			(layer "F.Fab")
		)
		(fp_line
			(start -2.249932 2.549906)
			(end -2.249932 -2.549906)
			(stroke
				(width 0.1)
				(type default)
			)
			(layer "F.Fab")
		)
		(fp_line
			(start 2.249932 -2.549906)
			(end 2.249932 2.549906)
			(stroke
				(width 0.1)
				(type default)
			)
			(layer "F.Fab")
		)
		(fp_line
			(start 2.249932 2.549906)
			(end -2.249932 2.549906)
			(stroke
				(width 0.1)
				(type default)
			)
			(layer "F.Fab")
		)
		(fp_poly
			(pts
				(xy -4.917186 -2.8829) (xy -4.917186 -1.8669) (xy -3.901186 -2.3749)
			)
			(stroke
				(width 0)
				(type default)
			)
			(fill yes)
			(layer "F.Fab")
		)
		(pad "1" smd rect
			(at -2.925064 -2.3749 270)
			(size 0.6096 1.3716)
			(layers "F.Cu" "F.Mask" "F.Paste")
			(net "TP_JTAG_SCM_SLOT3_R_TMS")
		)
		(pad "2" smd rect
			(at -2.925064 -1.625092 270)
			(size 0.4064 1.3716)
			(layers "F.Cu" "F.Mask" "F.Paste")
			(net "JTAG_SCM_PLD_R_TMS")
		)
		(pad "3" smd rect
			(at -2.925064 -0.975106 270)
			(size 0.4064 1.3716)
			(layers "F.Cu" "F.Mask" "F.Paste")
			(net "JTAG_SCM_TMS")
		)
		(pad "4" smd rect
			(at -2.925064 -0.32512 270)
			(size 0.4064 1.3716)
			(layers "F.Cu" "F.Mask" "F.Paste")
			(net "JTAG_SCM_PLD_R_TMS")
		)
		(pad "5" smd rect
			(at -2.925064 0.32512 270)
			(size 0.4064 1.3716)
			(layers "F.Cu" "F.Mask" "F.Paste")
			(net "JTAG_SCM_MUX_R_TMS")
		)
		(pad "6" smd rect
			(at -2.925064 0.975106 270)
			(size 0.4064 1.3716)
			(layers "F.Cu" "F.Mask" "F.Paste")
			(net "U160_EN_N")
		)
		(pad "7" smd rect
			(at -2.925064 1.625092 270)
			(size 0.4064 1.3716)
			(layers "F.Cu" "F.Mask" "F.Paste")
			(net "GND")
		)
		(pad "8" smd rect
			(at -2.925064 2.3749 270)
			(size 0.6096 1.3716)
			(layers "F.Cu" "F.Mask" "F.Paste")
			(net "GND")
		)
		(pad "9" smd rect
			(at 2.925064 2.3749 270)
			(size 0.6096 1.3716)
			(layers "F.Cu" "F.Mask" "F.Paste")
			(net "SCM_JTAG_MUX_S1")
		)
		(pad "10" smd rect
			(at 2.925064 1.625092 270)
			(size 0.4064 1.3716)
			(layers "F.Cu" "F.Mask" "F.Paste")
			(net "SCM_JTAG_MUX_S0_R1")
		)
		(pad "11" smd rect
			(at 2.925064 0.975106 270)
			(size 0.4064 1.3716)
			(layers "F.Cu" "F.Mask" "F.Paste")
			(net "JTAG_SCM_PLD_R_TCK")
		)
		(pad "12" smd rect
			(at 2.925064 0.32512 270)
			(size 0.4064 1.3716)
			(layers "F.Cu" "F.Mask" "F.Paste")
			(net "TP_JTAG_SCM_SLOT3_R_TCK")
		)
		(pad "13" smd rect
			(at 2.925064 -0.32512 270)
			(size 0.4064 1.3716)
			(layers "F.Cu" "F.Mask" "F.Paste")
			(net "JTAG_SCM_TCK")
		)
		(pad "14" smd rect
			(at 2.925064 -0.975106 270)
			(size 0.4064 1.3716)
			(layers "F.Cu" "F.Mask" "F.Paste")
			(net "JTAG_SCM_MUX_R_TCK")
		)
		(pad "15" smd rect
			(at 2.925064 -1.625092 270)
			(size 0.4064 1.3716)
			(layers "F.Cu" "F.Mask" "F.Paste")
			(net "JTAG_SCM_PLD_R_TCK")
		)
		(pad "16" smd rect
			(at 2.925064 -2.3749 270)
			(size 0.6096 1.3716)
			(layers "F.Cu" "F.Mask" "F.Paste")
			(net "P3V3_AUX")
		)
	)
	(footprint ""
		(layer "F.Cu")
		(at 364.155228 -29.886656 180)
		(property "Reference" "R1253"
			(at 0 0 180)
			(layer "F.SilkS")
			(hide yes)
			(effects
				(font
					(size 1.27 1.27)
				)
			)
		)
		(property "Value" ""
			(at 0 0 180)
			(layer "F.Fab")
			(effects
				(font
					(size 1.27 1.27)
				)
			)
		)
		(duplicate_pad_numbers_are_jumpers no)
		(fp_line
			(start 0.7874 0.4064)
			(end -0.7874 0.4064)
			(stroke
				(width 0.1524)
				(type default)
			)
			(layer "F.SilkS")
		)
		(fp_line
			(start 0.7874 -0.4064)
			(end 0.7874 0.4064)
			(stroke
				(width 0.1524)
				(type default)
			)
			(layer "F.SilkS")
		)
		(fp_line
			(start -0.7874 0.4064)
			(end -0.7874 -0.4064)
			(stroke
				(width 0.1524)
				(type default)
			)
			(layer "F.SilkS")
		)
		(fp_line
			(start -0.7874 -0.4064)
			(end 0.7874 -0.4064)
			(stroke
				(width 0.1524)
				(type default)
			)
			(layer "F.SilkS")
		)
		(fp_line
			(start 0.67945 0.3048)
			(end 0.120396 0.3048)
			(stroke
				(width 0.1)
				(type default)
			)
			(layer "F.Fab")
		)
		(fp_line
			(start 0.67945 -0.3048)
			(end 0.67945 0.3048)
			(stroke
				(width 0.1)
				(type default)
			)
			(layer "F.Fab")
		)
		(fp_line
			(start 0.12065 -0.2794)
			(end 0.12065 -0.3048)
			(stroke
				(width 0.1)
				(type default)
			)
			(layer "F.Fab")
		)
		(fp_line
			(start 0.12065 -0.3048)
			(end 0.67945 -0.3048)
			(stroke
				(width 0.1)
				(type default)
			)
			(layer "F.Fab")
		)
		(fp_line
			(start 0.120396 0.3048)
			(end 0.120396 0.2794)
			(stroke
				(width 0.1)
				(type default)
			)
			(layer "F.Fab")
		)
		(fp_line
			(start 0.120396 0.2794)
			(end -0.12065 0.2794)
			(stroke
				(width 0.1)
				(type default)
			)
			(layer "F.Fab")
		)
		(fp_line
			(start -0.12065 0.3048)
			(end -0.67945 0.3048)
			(stroke
				(width 0.1)
				(type default)
			)
			(layer "F.Fab")
		)
		(fp_line
			(start -0.12065 0.2794)
			(end -0.12065 0.3048)
			(stroke
				(width 0.1)
				(type default)
			)
			(layer "F.Fab")
		)
		(fp_line
			(start -0.12065 -0.2794)
			(end 0.12065 -0.2794)
			(stroke
				(width 0.1)
				(type default)
			)
			(layer "F.Fab")
		)
		(fp_line
			(start -0.12065 -0.305054)
			(end -0.12065 -0.2794)
			(stroke
				(width 0.1)
				(type default)
			)
			(layer "F.Fab")
		)
		(fp_line
			(start -0.67945 0.3048)
			(end -0.67945 -0.305054)
			(stroke
				(width 0.1)
				(type default)
			)
			(layer "F.Fab")
		)
		(fp_line
			(start -0.67945 -0.305054)
			(end -0.12065 -0.305054)
			(stroke
				(width 0.1)
				(type default)
			)
			(layer "F.Fab")
		)
		(pad "1" smd circle
			(at -0.40005 0 180)
			(size 0 0)
			(layers "F.Cu" "F.Mask" "F.Paste")
			(net "UART_LS_EN_N")
		)
		(pad "2" smd circle
			(at 0.40005 0 180)
			(size 0 0)
			(layers "F.Cu" "F.Mask" "F.Paste")
			(net "UART_LS_EN_R_N")
		)
	)
	(footprint ""
		(layer "F.Cu")
		(at 436.005732 -16.199866 -90)
		(property "Reference" "R41"
			(at 0 0 270)
			(layer "F.SilkS")
			(hide yes)
			(effects
				(font
					(size 1.27 1.27)
				)
			)
		)
		(property "Value" ""
			(at 0 0 270)
			(layer "F.Fab")
			(effects
				(font
					(size 1.27 1.27)
				)
			)
		)
		(duplicate_pad_numbers_are_jumpers no)
		(fp_line
			(start -0.7874 0.4064)
			(end -0.7874 -0.4064)
			(stroke
				(width 0.1524)
				(type default)
			)
			(layer "F.SilkS")
		)
		(fp_line
			(start 0.7874 0.4064)
			(end -0.7874 0.4064)
			(stroke
				(width 0.1524)
				(type default)
			)
			(layer "F.SilkS")
		)
		(fp_line
			(start -0.7874 -0.4064)
			(end 0.7874 -0.4064)
			(stroke
				(width 0.1524)
				(type default)
			)
			(layer "F.SilkS")
		)
		(fp_line
			(start 0.7874 -0.4064)
			(end 0.7874 0.4064)
			(stroke
				(width 0.1524)
				(type default)
			)
			(layer "F.SilkS")
		)
		(fp_line
			(start -0.67945 0.3048)
			(end -0.67945 -0.305054)
			(stroke
				(width 0.1)
				(type default)
			)
			(layer "F.Fab")
		)
		(fp_line
			(start -0.12065 0.3048)
			(end -0.67945 0.3048)
			(stroke
				(width 0.1)
				(type default)
			)
			(layer "F.Fab")
		)
		(fp_line
			(start 0.120396 0.3048)
			(end 0.120396 0.2794)
			(stroke
				(width 0.1)
				(type default)
			)
			(layer "F.Fab")
		)
		(fp_line
			(start 0.67945 0.3048)
			(end 0.120396 0.3048)
			(stroke
				(width 0.1)
				(type default)
			)
			(layer "F.Fab")
		)
		(fp_line
			(start -0.12065 0.2794)
			(end -0.12065 0.3048)
			(stroke
				(width 0.1)
				(type default)
			)
			(layer "F.Fab")
		)
		(fp_line
			(start 0.120396 0.2794)
			(end -0.12065 0.2794)
			(stroke
				(width 0.1)
				(type default)
			)
			(layer "F.Fab")
		)
		(fp_line
			(start -0.12065 -0.2794)
			(end 0.12065 -0.2794)
			(stroke
				(width 0.1)
				(type default)
			)
			(layer "F.Fab")
		)
		(fp_line
			(start 0.12065 -0.2794)
			(end 0.12065 -0.3048)
			(stroke
				(width 0.1)
				(type default)
			)
			(layer "F.Fab")
		)
		(fp_line
			(start 0.12065 -0.3048)
			(end 0.67945 -0.3048)
			(stroke
				(width 0.1)
				(type default)
			)
			(layer "F.Fab")
		)
		(fp_line
			(start 0.67945 -0.3048)
			(end 0.67945 0.3048)
			(stroke
				(width 0.1)
				(type default)
			)
			(layer "F.Fab")
		)
		(fp_line
			(start -0.67945 -0.305054)
			(end -0.12065 -0.305054)
			(stroke
				(width 0.1)
				(type default)
			)
			(layer "F.Fab")
		)
		(fp_line
			(start -0.12065 -0.305054)
			(end -0.12065 -0.2794)
			(stroke
				(width 0.1)
				(type default)
			)
			(layer "F.Fab")
		)
		(pad "1" smd circle
			(at -0.40005 0 270)
			(size 0 0)
			(layers "F.Cu" "F.Mask" "F.Paste")
			(net "OCP_SFF_ISO_BIF2_EN")
		)
		(pad "2" smd circle
			(at 0.40005 0 270)
			(size 0 0)
			(layers "F.Cu" "F.Mask" "F.Paste")
			(net "OCP_SFF_BIF2_R_N")
		)
	)
	(footprint ""
		(layer "F.Cu")
		(at 50.84953 -351.578672 90)
		(property "Reference" "PC435_7"
			(at 0 0 90)
			(layer "F.SilkS")
			(hide yes)
			(effects
				(font
					(size 1.27 1.27)
				)
			)
		)
		(property "Value" ""
			(at 0 0 90)
			(layer "F.Fab")
			(effects
				(font
					(size 1.27 1.27)
				)
			)
		)
		(duplicate_pad_numbers_are_jumpers no)
		(fp_line
			(start 0.7874 -0.4064)
			(end 0.7874 0.4064)
			(stroke
				(width 0.1524)
				(type default)
			)
			(layer "F.SilkS")
		)
		(fp_line
			(start -0.7874 -0.4064)
			(end 0.7874 -0.4064)
			(stroke
				(width 0.1524)
				(type default)
			)
			(layer "F.SilkS")
		)
		(fp_line
			(start 0.7874 0.4064)
			(end -0.7874 0.4064)
			(stroke
				(width 0.1524)
				(type default)
			)
			(layer "F.SilkS")
		)
		(fp_line
			(start -0.7874 0.4064)
			(end -0.7874 -0.4064)
			(stroke
				(width 0.1524)
				(type default)
			)
			(layer "F.SilkS")
		)
		(fp_line
			(start -0.12065 -0.305054)
			(end -0.12065 -0.2794)
			(stroke
				(width 0.1)
				(type default)
			)
			(layer "F.Fab")
		)
		(fp_line
			(start -0.67945 -0.305054)
			(end -0.12065 -0.305054)
			(stroke
				(width 0.1)
				(type default)
			)
			(layer "F.Fab")
		)
		(fp_line
			(start 0.67945 -0.3048)
			(end 0.67945 0.3048)
			(stroke
				(width 0.1)
				(type default)
			)
			(layer "F.Fab")
		)
		(fp_line
			(start 0.12065 -0.3048)
			(end 0.67945 -0.3048)
			(stroke
				(width 0.1)
				(type default)
			)
			(layer "F.Fab")
		)
		(fp_line
			(start 0.12065 -0.2794)
			(end 0.12065 -0.3048)
			(stroke
				(width 0.1)
				(type default)
			)
			(layer "F.Fab")
		)
		(fp_line
			(start -0.12065 -0.2794)
			(end 0.12065 -0.2794)
			(stroke
				(width 0.1)
				(type default)
			)
			(layer "F.Fab")
		)
		(fp_line
			(start 0.120396 0.2794)
			(end -0.12065 0.2794)
			(stroke
				(width 0.1)
				(type default)
			)
			(layer "F.Fab")
		)
		(fp_line
			(start -0.12065 0.2794)
			(end -0.12065 0.3048)
			(stroke
				(width 0.1)
				(type default)
			)
			(layer "F.Fab")
		)
		(fp_line
			(start 0.67945 0.3048)
			(end 0.120396 0.3048)
			(stroke
				(width 0.1)
				(type default)
			)
			(layer "F.Fab")
		)
		(fp_line
			(start 0.120396 0.3048)
			(end 0.120396 0.2794)
			(stroke
				(width 0.1)
				(type default)
			)
			(layer "F.Fab")
		)
		(fp_line
			(start -0.12065 0.3048)
			(end -0.67945 0.3048)
			(stroke
				(width 0.1)
				(type default)
			)
			(layer "F.Fab")
		)
		(fp_line
			(start -0.67945 0.3048)
			(end -0.67945 -0.305054)
			(stroke
				(width 0.1)
				(type default)
			)
			(layer "F.Fab")
		)
		(pad "1" smd circle
			(at -0.40005 0 90)
			(size 0 0)
			(layers "F.Cu" "F.Mask" "F.Paste")
			(net "PVDDCR_CPU1_P1_VCCS")
		)
		(pad "2" smd circle
			(at 0.40005 0 90)
			(size 0 0)
			(layers "F.Cu" "F.Mask" "F.Paste")
			(net "GND")
		)
	)
)
